(kicad_pcb
	(version 20241229)
	(generator "pcbnew")
	(generator_version "9.0")
	(general
		(thickness 1.62)
		(legacy_teardrops no)
	)
	(paper "A4")
	(title_block
		(title "OCuLink to 10GbE adapter")
		(date "2026-02-23")
		(rev "1.1.0")
		(company "Antmicro Ltd")
		(comment 1 "www.antmicro.com")
		(comment 9 "footprint 265 of 510 (U9), pads 166-244 of 503")
	)
	(layers
		(0 "F.Cu" signal)
		(4 "In1.Cu" signal)
		(6 "In2.Cu" signal)
		(8 "In3.Cu" signal)
		(10 "In4.Cu" signal)
		(12 "In5.Cu" signal)
		(14 "In6.Cu" signal)
		(2 "B.Cu" signal)
		(9 "F.Adhes" user "F.Adhesive")
		(11 "B.Adhes" user "B.Adhesive")
		(13 "F.Paste" user)
		(15 "B.Paste" user)
		(5 "F.SilkS" user "F.Silkscreen")
		(7 "B.SilkS" user "B.Silkscreen")
		(1 "F.Mask" user)
		(3 "B.Mask" user)
		(17 "Dwgs.User" user "User.Drawings")
		(19 "Cmts.User" user "User.Comments")
		(21 "Eco1.User" user "User.Eco1")
		(23 "Eco2.User" user "User.Eco2")
		(25 "Edge.Cuts" user)
		(27 "Margin" user)
		(31 "F.CrtYd" user "F.Courtyard")
		(29 "B.CrtYd" user "B.Courtyard")
		(35 "F.Fab" user)
		(33 "B.Fab" user)
	)
	(footprint "antmicro-footprints:FCBGA-503_22x22mm_Layout21x24_P1mm"
		(locked yes)
		(layer "F.Cu")
		(at 84.975 100 180)
		(property "Reference" "U9"
			(at -11.275 11.4 0)
			(layer "F.SilkS")
			(effects
				(font
					(size 0.7 0.7)
					(thickness 0.15)
				)
				(justify right bottom)
			)
		)
		(property "Value" "EZX710AT2_S_LMR5"
			(at -11.4 12.5 0)
			(layer "F.Fab")
			(hide yes)
			(effects
				(font
					(size 0.7 0.7)
					(thickness 0.15)
				)
				(justify right top)
			)
		)
		(property "Datasheet" "https://www.google.com/url?sa=t&source=web&rct=j&opi=89978449&url=https://cdrdv2-public.intel.com/596333/596333_X710-TM4_Datasheet_v_2_4.pdf&ved=2ahUKEwiSuv20_sCOAxXVCRAIHdxGO_UQFnoECBEQAQ&usg=AOvVaw1CjGyrGWE8ZvOdw4VBsY6U"
			(at -16.625 -13.91 0)
			(layer "F.Fab")
			(hide yes)
			(effects
				(font
					(size 0.7 0.7)
					(thickness 0.15)
				)
				(justify right top)
			)
		)
		(property "Description" "Ethernet ICs Intel Ethernet Controller 10 Gigabit X7"
			(at -12.015 -0.89 0)
			(layer "F.Fab")
			(hide yes)
			(effects
				(font
					(size 0.7 0.7)
					(thickness 0.15)
				)
				(justify right top)
			)
		)
		(property "MPN" "EZX710AT2 S LMR5"
			(at 0 0 180)
			(unlocked yes)
			(layer "F.Fab")
			(hide yes)
			(effects
				(font
					(size 1 1)
					(thickness 0.15)
				)
			)
		)
		(property "Manufacturer" "Intel"
			(at 0 0 180)
			(unlocked yes)
			(layer "F.Fab")
			(hide yes)
			(effects
				(font
					(size 1 1)
					(thickness 0.15)
				)
			)
		)
		(property "Author" "Antmicro"
			(at 0 0 180)
			(unlocked yes)
			(layer "F.Fab")
			(hide yes)
			(effects
				(font
					(size 1 1)
					(thickness 0.15)
				)
			)
		)
		(property "License" "Apache-2.0"
			(at 0 0 180)
			(unlocked yes)
			(layer "F.Fab")
			(hide yes)
			(effects
				(font
					(size 1 1)
					(thickness 0.15)
				)
			)
		)
		(sheetname "/X710-AT2 power/")
		(sheetfile "x710-at2-power.kicad_sch")
		(attr smd)
		(pad "D40" smd circle
			(at 9.25 -7.355 180)
			(size 0.5 0.5)
			(layers "F.Cu" "F.Mask" "F.Paste")
			(net 28 "GND")
			(pinfunction "AVSS")
			(pintype "passive")
		)
		(pad "D42" smd circle
			(at 10.25 -7.355 180)
			(size 0.5 0.5)
			(layers "F.Cu" "F.Mask" "F.Paste")
			(net 153 "/X710-AT2 Misc/50MHZ_XTAL.+")
			(pinfunction "XTAL_P")
			(pintype "input")
		)
		(pad "E1" smd circle
			(at -10.25 -6.49 180)
			(size 0.5 0.5)
			(layers "F.Cu" "F.Mask" "F.Paste")
			(net 100 "/X710-AT2 Misc/AUX_PWR")
			(pinfunction "AUX_PWR")
			(pintype "tri_state")
		)
		(pad "E3" smd circle
			(at -9.25 -6.49 180)
			(size 0.5 0.5)
			(layers "F.Cu" "F.Mask" "F.Paste")
			(net 133 "/X710-AT2 Misc/MAIN_PWR_OK")
			(pinfunction "MAIN_PWR_OK")
			(pintype "input")
		)
		(pad "E5" smd circle
			(at -8.25 -6.49 180)
			(size 0.5 0.5)
			(layers "F.Cu" "F.Mask" "F.Paste")
			(net 141 "/X710-AT2 10GbE/~{PHY_RESET_3V3_R}")
			(pinfunction "SDP0_0")
			(pintype "tri_state")
		)
		(pad "E7" smd circle
			(at -7.25 -6.49 180)
			(size 0.5 0.5)
			(layers "F.Cu" "F.Mask" "F.Paste")
			(net 256 "unconnected-(U9C-SDP2_2-PadE7)")
			(pinfunction "SDP2_2")
			(pintype "passive+no_connect")
		)
		(pad "E9" smd circle
			(at -6.25 -6.49 180)
			(size 0.5 0.5)
			(layers "F.Cu" "F.Mask" "F.Paste")
			(net 260 "unconnected-(U9F-SYNCE_LOCK_1-PadE9)")
			(pinfunction "SYNCE_LOCK_1")
			(pintype "output+no_connect")
		)
		(pad "E11" smd circle
			(at -5.25 -6.49 180)
			(size 0.5 0.5)
			(layers "F.Cu" "F.Mask" "F.Paste")
			(net 185 "unconnected-(U9F-SYNCE_LOCK_2-PadE11)")
			(pinfunction "SYNCE_LOCK_2")
			(pintype "output+no_connect")
		)
		(pad "E13" smd circle
			(at -4.25 -6.49 180)
			(size 0.5 0.5)
			(layers "F.Cu" "F.Mask" "F.Paste")
			(net 209 "unconnected-(U9F-SYNCE_CLKOUT_3-PadE13)")
			(pinfunction "SYNCE_CLKOUT_3")
			(pintype "output+no_connect")
		)
		(pad "E15" smd circle
			(at -3.25 -6.49 180)
			(size 0.5 0.5)
			(layers "F.Cu" "F.Mask" "F.Paste")
			(net 136 "/X710-AT2 Misc/PHY_TDI")
			(pinfunction "PHY_TDI")
			(pintype "input")
		)
		(pad "E17" smd circle
			(at -2.25 -6.49 180)
			(size 0.5 0.5)
			(layers "F.Cu" "F.Mask" "F.Paste")
			(net 134 "/X710-AT2 Misc/PHY_TCK")
			(pinfunction "PHY_TCK")
			(pintype "input")
		)
		(pad "E19" smd circle
			(at -1.25 -6.49 180)
			(size 0.5 0.5)
			(layers "F.Cu" "F.Mask" "F.Paste")
			(net 292 "/X710-AT2 RSVD/RSVDE19_1P88V")
			(pinfunction "RSVDE19_1P88V")
			(pintype "passive")
		)
		(pad "E21" smd circle
			(at -0.25 -6.49 180)
			(size 0.5 0.5)
			(layers "F.Cu" "F.Mask" "F.Paste")
			(net 28 "GND")
			(pinfunction "RSVDE21_VSS")
			(pintype "passive")
		)
		(pad "E23" smd circle
			(at 0.75 -6.49 180)
			(size 0.5 0.5)
			(layers "F.Cu" "F.Mask" "F.Paste")
			(net 28 "GND")
			(pinfunction "RSVDE23_VSS")
			(pintype "passive")
		)
		(pad "E25" smd circle
			(at 1.75 -6.49 180)
			(size 0.5 0.5)
			(layers "F.Cu" "F.Mask" "F.Paste")
			(net 28 "GND")
			(pinfunction "RSVDE25_VSS")
			(pintype "passive")
		)
		(pad "E27" smd circle
			(at 2.75 -6.49 180)
			(size 0.5 0.5)
			(layers "F.Cu" "F.Mask" "F.Paste")
			(net 10 "AVDDH")
			(pinfunction "P1_AVDDH")
			(pintype "power_in")
		)
		(pad "E29" smd circle
			(at 3.75 -6.49 180)
			(size 0.5 0.5)
			(layers "F.Cu" "F.Mask" "F.Paste")
			(net 10 "AVDDH")
			(pinfunction "P1_AVDDH")
			(pintype "passive")
		)
		(pad "E31" smd circle
			(at 4.75 -6.49 180)
			(size 0.5 0.5)
			(layers "F.Cu" "F.Mask" "F.Paste")
			(net 28 "GND")
			(pinfunction "AVSS")
			(pintype "passive")
		)
		(pad "E33" smd circle
			(at 5.75 -6.49 180)
			(size 0.5 0.5)
			(layers "F.Cu" "F.Mask" "F.Paste")
			(net 28 "GND")
			(pinfunction "AVSS")
			(pintype "passive")
		)
		(pad "E35" smd circle
			(at 6.75 -6.49 180)
			(size 0.5 0.5)
			(layers "F.Cu" "F.Mask" "F.Paste")
			(net 10 "AVDDH")
			(pinfunction "P0_AVDDH")
			(pintype "power_in")
		)
		(pad "E37" smd circle
			(at 7.75 -6.49 180)
			(size 0.5 0.5)
			(layers "F.Cu" "F.Mask" "F.Paste")
			(net 10 "AVDDH")
			(pinfunction "P0_AVDDH")
			(pintype "passive")
		)
		(pad "E39" smd circle
			(at 8.75 -6.49 180)
			(size 0.5 0.5)
			(layers "F.Cu" "F.Mask" "F.Paste")
			(net 84 "/X710-AT2 10GbE/BIAS_RDAC")
			(pinfunction "BIAS_RDAC")
			(pintype "passive")
		)
		(pad "E41" smd circle
			(at 9.75 -6.49 180)
			(size 0.5 0.5)
			(layers "F.Cu" "F.Mask" "F.Paste")
			(net 191 "/X710-AT2 Misc/50MHZ_XTAL.-")
			(pinfunction "XTAL_N")
			(pintype "input")
		)
		(pad "F2" smd circle
			(at -9.75 -5.625 180)
			(size 0.5 0.5)
			(layers "F.Cu" "F.Mask" "F.Paste")
			(net 363 "/X710-AT2 Misc/NCSI.TXD_0")
			(pinfunction "NCSI_TXD_0")
			(pintype "input")
		)
		(pad "F4" smd circle
			(at -8.75 -5.625 180)
			(size 0.5 0.5)
			(layers "F.Cu" "F.Mask" "F.Paste")
			(net 159 "Net-(U9D-NCSI_ARB_OUT)")
			(pinfunction "NCSI_ARB_OUT")
			(pintype "output")
		)
		(pad "F6" smd circle
			(at -7.75 -5.625 180)
			(size 0.5 0.5)
			(layers "F.Cu" "F.Mask" "F.Paste")
			(net 211 "unconnected-(U9C-SDP2_0-PadF6)")
			(pinfunction "SDP2_0")
			(pintype "passive+no_connect")
		)
		(pad "F8" smd circle
			(at -6.75 -5.625 180)
			(size 0.5 0.5)
			(layers "F.Cu" "F.Mask" "F.Paste")
			(net 238 "unconnected-(U9F-SYNCE_LOCK_0-PadF8)")
			(pinfunction "SYNCE_LOCK_0")
			(pintype "output+no_connect")
		)
		(pad "F10" smd circle
			(at -5.75 -5.625 180)
			(size 0.5 0.5)
			(layers "F.Cu" "F.Mask" "F.Paste")
			(net 258 "unconnected-(U9F-SYNCE_CLKOUT_1-PadF10)")
			(pinfunction "SYNCE_CLKOUT_1")
			(pintype "output+no_connect")
		)
		(pad "F12" smd circle
			(at -4.75 -5.625 180)
			(size 0.5 0.5)
			(layers "F.Cu" "F.Mask" "F.Paste")
			(net 218 "unconnected-(U9F-SYNCE_LOCK_3-PadF12)")
			(pinfunction "SYNCE_LOCK_3")
			(pintype "output+no_connect")
		)
		(pad "F14" smd circle
			(at -3.75 -5.625 180)
			(size 0.5 0.5)
			(layers "F.Cu" "F.Mask" "F.Paste")
			(net 287 "/X710-AT2 10GbE/~{P1_INT}")
			(pinfunction "P1_INT_MLC")
			(pintype "passive")
		)
		(pad "F16" smd circle
			(at -2.75 -5.625 180)
			(size 0.5 0.5)
			(layers "F.Cu" "F.Mask" "F.Paste")
			(net 137 "/X710-AT2 Misc/PHY_TDO")
			(pinfunction "PHY_TDO")
			(pintype "open_collector")
		)
		(pad "F18" smd circle
			(at -1.75 -5.625 180)
			(size 0.5 0.5)
			(layers "F.Cu" "F.Mask" "F.Paste")
			(net 28 "GND")
			(pinfunction "RSVDF18_VSS")
			(pintype "passive")
		)
		(pad "F20" smd circle
			(at -0.75 -5.625 180)
			(size 0.5 0.5)
			(layers "F.Cu" "F.Mask" "F.Paste")
			(net 28 "GND")
			(pinfunction "RSVDF20_VSS")
			(pintype "passive")
		)
		(pad "F22" smd circle
			(at 0.25 -5.625 180)
			(size 0.5 0.5)
			(layers "F.Cu" "F.Mask" "F.Paste")
			(net 28 "GND")
			(pinfunction "RSVDF22_VSS")
			(pintype "passive")
		)
		(pad "F24" smd circle
			(at 1.25 -5.625 180)
			(size 0.5 0.5)
			(layers "F.Cu" "F.Mask" "F.Paste")
			(net 28 "GND")
			(pinfunction "VSS")
			(pintype "power_in")
		)
		(pad "F26" smd circle
			(at 2.25 -5.625 180)
			(size 0.5 0.5)
			(layers "F.Cu" "F.Mask" "F.Paste")
			(net 28 "GND")
			(pinfunction "VSS")
			(pintype "passive")
		)
		(pad "F28" smd circle
			(at 3.25 -5.625 180)
			(size 0.5 0.5)
			(layers "F.Cu" "F.Mask" "F.Paste")
			(net 28 "GND")
			(pinfunction "VSS")
			(pintype "passive")
		)
		(pad "F30" smd circle
			(at 4.25 -5.625 180)
			(size 0.5 0.5)
			(layers "F.Cu" "F.Mask" "F.Paste")
			(net 28 "GND")
			(pinfunction "VSS")
			(pintype "passive")
		)
		(pad "F32" smd circle
			(at 5.25 -5.625 180)
			(size 0.5 0.5)
			(layers "F.Cu" "F.Mask" "F.Paste")
			(net 28 "GND")
			(pinfunction "VSS")
			(pintype "passive")
		)
		(pad "F34" smd circle
			(at 6.25 -5.625 180)
			(size 0.5 0.5)
			(layers "F.Cu" "F.Mask" "F.Paste")
			(net 28 "GND")
			(pinfunction "VSS")
			(pintype "passive")
		)
		(pad "F36" smd circle
			(at 7.25 -5.625 180)
			(size 0.5 0.5)
			(layers "F.Cu" "F.Mask" "F.Paste")
			(net 28 "GND")
			(pinfunction "VSS")
			(pintype "passive")
		)
		(pad "F38" smd circle
			(at 8.25 -5.625 180)
			(size 0.5 0.5)
			(layers "F.Cu" "F.Mask" "F.Paste")
			(net 28 "GND")
			(pinfunction "RSVDF38_VSS")
			(pintype "passive")
		)
		(pad "F40" smd circle
			(at 9.25 -5.625 180)
			(size 0.5 0.5)
			(layers "F.Cu" "F.Mask" "F.Paste")
			(net 28 "GND")
			(pinfunction "AVSS")
			(pintype "passive")
		)
		(pad "F42" smd circle
			(at 10.25 -5.625 180)
			(size 0.5 0.5)
			(layers "F.Cu" "F.Mask" "F.Paste")
			(net 28 "GND")
			(pinfunction "AVSS")
			(pintype "passive")
		)
		(pad "G1" smd circle
			(at -10.25 -4.76 180)
			(size 0.5 0.5)
			(layers "F.Cu" "F.Mask" "F.Paste")
			(net 361 "/X710-AT2 Misc/NCSI.TXD_1")
			(pinfunction "NCSI_TXD_1")
			(pintype "input")
		)
		(pad "G3" smd circle
			(at -9.25 -4.76 180)
			(size 0.5 0.5)
			(layers "F.Cu" "F.Mask" "F.Paste")
			(net 368 "/X710-AT2 Misc/NCSI.ARB_IN")
			(pinfunction "NCSI_ARB_IN")
			(pintype "input")
		)
		(pad "G5" smd circle
			(at -8.25 -4.76 180)
			(size 0.5 0.5)
			(layers "F.Cu" "F.Mask" "F.Paste")
			(net 198 "/X710-AT2 10GbE/~{P0_INT_R}")
			(pinfunction "SDP0_1")
			(pintype "tri_state")
		)
		(pad "G7" smd circle
			(at -7.25 -4.76 180)
			(size 0.5 0.5)
			(layers "F.Cu" "F.Mask" "F.Paste")
			(net 371 "unconnected-(U9C-SDP2_3-PadG7)")
			(pinfunction "SDP2_3")
			(pintype "passive+no_connect")
		)
		(pad "G9" smd circle
			(at -6.25 -4.76 180)
			(size 0.5 0.5)
			(layers "F.Cu" "F.Mask" "F.Paste")
			(net 207 "unconnected-(U9F-SYNCE_CLKOUT_0-PadG9)")
			(pinfunction "SYNCE_CLKOUT_0")
			(pintype "output+no_connect")
		)
		(pad "G11" smd circle
			(at -5.25 -4.76 180)
			(size 0.5 0.5)
			(layers "F.Cu" "F.Mask" "F.Paste")
			(net 254 "unconnected-(U9F-SYNCE_CLKOUT_2-PadG11)")
			(pinfunction "SYNCE_CLKOUT_2")
			(pintype "output+no_connect")
		)
		(pad "G13" smd circle
			(at -4.25 -4.76 180)
			(size 0.5 0.5)
			(layers "F.Cu" "F.Mask" "F.Paste")
			(net 223 "unconnected-(U9F-RSVDG13_NC-PadG13)")
			(pinfunction "RSVDG13_NC")
			(pintype "passive+no_connect")
		)
		(pad "G15" smd circle
			(at -3.25 -4.76 180)
			(size 0.5 0.5)
			(layers "F.Cu" "F.Mask" "F.Paste")
			(net 224 "unconnected-(U9F-RSVDG15_NC-PadG15)")
			(pinfunction "RSVDG15_NC")
			(pintype "passive+no_connect")
		)
		(pad "G17" smd circle
			(at -2.25 -4.76 180)
			(size 0.5 0.5)
			(layers "F.Cu" "F.Mask" "F.Paste")
			(net 294 "/X710-AT2 10GbE/TPIN_5")
			(pinfunction "TPIN_5")
			(pintype "passive")
		)
		(pad "G19" smd circle
			(at -1.25 -4.76 180)
			(size 0.5 0.5)
			(layers "F.Cu" "F.Mask" "F.Paste")
			(net 28 "GND")
			(pinfunction "RSVDG19_VSS")
			(pintype "passive")
		)
		(pad "G21" smd circle
			(at -0.25 -4.76 180)
			(size 0.5 0.5)
			(layers "F.Cu" "F.Mask" "F.Paste")
			(net 28 "GND")
			(pinfunction "RSVDG21_VSS")
			(pintype "passive")
		)
		(pad "G23" smd circle
			(at 0.75 -4.76 180)
			(size 0.5 0.5)
			(layers "F.Cu" "F.Mask" "F.Paste")
			(net 28 "GND")
			(pinfunction "RSVDG23_VSS")
			(pintype "passive")
		)
		(pad "G25" smd circle
			(at 1.75 -4.76 180)
			(size 0.5 0.5)
			(layers "F.Cu" "F.Mask" "F.Paste")
			(net 18 "+1V88")
			(pinfunction "VDDIO1")
			(pintype "power_in")
		)
		(pad "G27" smd circle
			(at 2.75 -4.76 180)
			(size 0.5 0.5)
			(layers "F.Cu" "F.Mask" "F.Paste")
			(net 6 "DVDD")
			(pinfunction "DVDD")
			(pintype "power_in")
		)
		(pad "G29" smd circle
			(at 3.75 -4.76 180)
			(size 0.5 0.5)
			(layers "F.Cu" "F.Mask" "F.Paste")
			(net 6 "DVDD")
			(pinfunction "DVDD")
			(pintype "passive")
		)
		(pad "G31" smd circle
			(at 4.75 -4.76 180)
			(size 0.5 0.5)
			(layers "F.Cu" "F.Mask" "F.Paste")
			(net 6 "DVDD")
			(pinfunction "DVDD")
			(pintype "passive")
		)
		(pad "G33" smd circle
			(at 5.75 -4.76 180)
			(size 0.5 0.5)
			(layers "F.Cu" "F.Mask" "F.Paste")
			(net 6 "DVDD")
			(pinfunction "DVDD")
			(pintype "passive")
		)
		(pad "G35" smd circle
			(at 6.75 -4.76 180)
			(size 0.5 0.5)
			(layers "F.Cu" "F.Mask" "F.Paste")
			(net 6 "DVDD")
			(pinfunction "DVDD")
			(pintype "passive")
		)
		(pad "G37" smd circle
			(at 7.75 -4.76 180)
			(size 0.5 0.5)
			(layers "F.Cu" "F.Mask" "F.Paste")
			(net 18 "+1V88")
			(pinfunction "VDDIO1")
			(pintype "passive")
		)
		(pad "G39" smd circle
			(at 8.75 -4.76 180)
			(size 0.5 0.5)
			(layers "F.Cu" "F.Mask" "F.Paste")
			(net 27 "PLL_VDD")
			(pinfunction "PLL_VDD")
			(pintype "power_in")
		)
		(pad "G41" smd circle
			(at 9.75 -4.76 180)
			(size 0.5 0.5)
			(layers "F.Cu" "F.Mask" "F.Paste")
			(net 28 "GND")
			(pinfunction "AVSS")
			(pintype "passive")
		)
		(pad "H2" smd circle
			(at -9.75 -3.895 180)
			(size 0.5 0.5)
			(layers "F.Cu" "F.Mask" "F.Paste")
			(net 367 "/X710-AT2 Misc/NCSI.REF_CLK")
			(pinfunction "NCSI_CLK_IN")
			(pintype "input")
		)
		(pad "H4" smd circle
			(at -8.75 -3.895 180)
			(size 0.5 0.5)
			(layers "F.Cu" "F.Mask" "F.Paste")
			(net 366 "/X710-AT2 Misc/NCSI.TX_EN")
			(pinfunction "NCSI_TX_EN")
			(pintype "input")
		)
		(pad "H6" smd circle
			(at -7.75 -3.895 180)
			(size 0.5 0.5)
			(layers "F.Cu" "F.Mask" "F.Paste")
			(net 296 "unconnected-(U9C-SDP1_3-PadH6)")
			(pinfunction "SDP1_3")
			(pintype "passive+no_connect")
		)
		(pad "H8" smd circle
			(at -6.75 -3.895 180)
			(size 0.5 0.5)
			(layers "F.Cu" "F.Mask" "F.Paste")
			(net 212 "unconnected-(U9D-GPIO_4-PadH8)")
			(pinfunction "GPIO_4")
			(pintype "passive+no_connect")
		)
		(pad "H10" smd circle
			(at -5.75 -3.895 180)
			(size 0.5 0.5)
			(layers "F.Cu" "F.Mask" "F.Paste")
			(net 189 "unconnected-(U9F-P1_PTP_SYNC0-PadH10)")
			(pinfunction "P1_PTP_SYNC0")
			(pintype "passive+no_connect")
		)
		(pad "H12" smd circle
			(at -4.75 -3.895 180)
			(size 0.5 0.5)
			(layers "F.Cu" "F.Mask" "F.Paste")
			(net 345 "unconnected-(U9F-P1_PTP_SYNC1-PadH12)")
			(pinfunction "P1_PTP_SYNC1")
			(pintype "passive+no_connect")
		)
		(pad "H14" smd circle
			(at -3.75 -3.895 180)
			(size 0.5 0.5)
			(layers "F.Cu" "F.Mask" "F.Paste")
			(net 227 "unconnected-(U9F-RSVDH14_NC-PadH14)")
			(pinfunction "RSVDH14_NC")
			(pintype "passive+no_connect")
		)
		(pad "H16" smd circle
			(at -2.75 -3.895 180)
			(size 0.5 0.5)
			(layers "F.Cu" "F.Mask" "F.Paste")
			(net 242 "unconnected-(U9F-RSVDH16_NC-PadH16)")
			(pinfunction "RSVDH16_NC")
			(pintype "passive+no_connect")
		)
		(pad "H18" smd circle
			(at -1.75 -3.895 180)
			(size 0.5 0.5)
			(layers "F.Cu" "F.Mask" "F.Paste")
			(net 28 "GND")
			(pinfunction "RSVH18_VSS")
			(pintype "passive")
		)
		(pad "H20" smd circle
			(at -0.75 -3.895 180)
			(size 0.5 0.5)
			(layers "F.Cu" "F.Mask" "F.Paste")
			(net 293 "/X710-AT2 10GbE/TPIN_3")
			(pinfunction "TPIN_3")
			(pintype "passive")
		)
		(pad "H22" smd circle
			(at 0.25 -3.895 180)
			(size 0.5 0.5)
			(layers "F.Cu" "F.Mask" "F.Paste")
			(net 28 "GND")
			(pinfunction "RSVDH22_VSS")
			(pintype "passive")
		)
		(pad "H24" smd circle
			(at 1.25 -3.895 180)
			(size 0.5 0.5)
			(layers "F.Cu" "F.Mask" "F.Paste")
			(net 28 "GND")
			(pinfunction "RSVDH24_VSS")
			(pintype "passive")
		)
		(pad "H26" smd circle
			(at 2.25 -3.895 180)
			(size 0.5 0.5)
			(layers "F.Cu" "F.Mask" "F.Paste")
			(net 28 "GND")
			(pinfunction "VSSA")
			(pintype "passive")
		)
		(pad "H28" smd circle
			(at 3.25 -3.895 180)
			(size 0.5 0.5)
			(layers "F.Cu" "F.Mask" "F.Paste")
			(net 28 "GND")
			(pinfunction "VSSA")
			(pintype "passive")
		)
	)
)
